# S9S_MB_2U (Grand Teton) — schematic netlist excerpt (pin names and nets, part order shuffled) for the footprints in the layout excerpt that follows; sources: Cadence DE-HDL packaged netlist, KiCad conversion of 03242023_DA0F0TMBIJ0_F0T_Motherboard_J_brd_V01_OCP.brd

R3470  Q_RES  10K 1% EMPTY  pkg 0402LF  page 147 : A = P3V3_AUX ; B = GPU_WP_HW_CTRL_N
C724  Q_CAP_DIFFBUS  DIFF BUS_0.22UF 6.3V 20% X6S  pkg C0201  page 176 : \1\ = P5E_CPU1_PE0_TX_C_DN<8> ; \2\ = P5E_CPU1_PE0_TX_DN<8>
PC2212  Q_CAP  1UF 25V 10% X6S  pkg C0402  page 192 : A = GND ; B = P3V3_E1S_REG_0

(kicad_pcb
	(version 20260206)
	(generator "pcbnew")
	(generator_version "10.0")
	(general
		(thickness 1.6)
		(legacy_teardrops no)
	)
	(paper "A4")
	(title_block
		(title "03242023_DA0F0TMBIJ0_F0T_Motherboard_J_brd_V01_OCP.brd")
		(comment 1 "Grand Teton / footprints 1663-1665 of 6105")
	)
	(layers
		(0 "F.Cu" signal "TOP")
		(4 "In1.Cu" signal "GND")
		(6 "In2.Cu" signal "IN1")
		(8 "In3.Cu" signal "GND1")
		(10 "In4.Cu" signal "IN2")
		(12 "In5.Cu" signal "GND2")
		(14 "In6.Cu" signal "IN3")
		(16 "In7.Cu" signal "GND3")
		(18 "In8.Cu" signal "VCC")
		(20 "In9.Cu" signal "VCC1")
		(22 "In10.Cu" signal "GND4")
		(24 "In11.Cu" signal "IN4")
		(26 "In12.Cu" signal "GND5")
		(28 "In13.Cu" signal "IN5")
		(30 "In14.Cu" signal "GND6")
		(32 "In15.Cu" signal "IN6")
		(34 "In16.Cu" signal "GND7")
		(2 "B.Cu" signal "BOTTOM")
		(9 "F.Adhes" user "F.Adhesive")
		(11 "B.Adhes" user "B.Adhesive")
		(13 "F.Paste" user "Package Geometry/Pastemask Top")
		(15 "B.Paste" user "Package Geometry/Pastemask Bottom")
		(5 "F.SilkS" user "Ref Des/Silkscreen Top")
		(7 "B.SilkS" user "Ref Des/Silkscreen Bottom")
		(1 "F.Mask" user "Board Geometry/Soldermask Top")
		(3 "B.Mask" user "Board Geometry/Soldermask Bottom")
		(17 "Dwgs.User" user "User.Drawings")
		(19 "Cmts.User" user "User.Comments")
		(21 "Eco1.User" user "User.Eco1")
		(23 "Eco2.User" user "User.Eco2")
		(25 "Edge.Cuts" user "Board Geometry/Outline")
		(27 "Margin" user)
		(31 "F.CrtYd" user "Package Geometry/Place Bound Top")
		(29 "B.CrtYd" user "Package Geometry/Place Bound Bottom")
		(35 "F.Fab" user "Ref Des/Assembly Top")
		(33 "B.Fab" user "Ref Des/Assembly Bottom")
	)
	(footprint ""
		(layer "F.Cu")
		(at 424.223942 -401.655534)
		(property "Reference" "R3470"
			(at 0 0 0)
			(layer "F.SilkS")
			(hide yes)
			(effects
				(font
					(size 1.27 1.27)
				)
			)
		)
		(property "Value" ""
			(at 0 0 0)
			(layer "F.Fab")
			(effects
				(font
					(size 1.27 1.27)
				)
			)
		)
		(duplicate_pad_numbers_are_jumpers no)
		(fp_line
			(start -0.7874 -0.4064)
			(end 0.7874 -0.4064)
			(stroke
				(width 0.1524)
				(type default)
			)
			(layer "F.SilkS")
		)
		(fp_line
			(start -0.7874 0.4064)
			(end -0.7874 -0.4064)
			(stroke
				(width 0.1524)
				(type default)
			)
			(layer "F.SilkS")
		)
		(fp_line
			(start 0.7874 -0.4064)
			(end 0.7874 0.4064)
			(stroke
				(width 0.1524)
				(type default)
			)
			(layer "F.SilkS")
		)
		(fp_line
			(start 0.7874 0.4064)
			(end -0.7874 0.4064)
			(stroke
				(width 0.1524)
				(type default)
			)
			(layer "F.SilkS")
		)
		(fp_line
			(start -0.67945 -0.305054)
			(end -0.12065 -0.305054)
			(stroke
				(width 0.1)
				(type default)
			)
			(layer "F.Fab")
		)
		(fp_line
			(start -0.67945 0.3048)
			(end -0.67945 -0.305054)
			(stroke
				(width 0.1)
				(type default)
			)
			(layer "F.Fab")
		)
		(fp_line
			(start -0.12065 -0.305054)
			(end -0.12065 -0.2794)
			(stroke
				(width 0.1)
				(type default)
			)
			(layer "F.Fab")
		)
		(fp_line
			(start -0.12065 -0.2794)
			(end 0.12065 -0.2794)
			(stroke
				(width 0.1)
				(type default)
			)
			(layer "F.Fab")
		)
		(fp_line
			(start -0.12065 0.2794)
			(end -0.12065 0.3048)
			(stroke
				(width 0.1)
				(type default)
			)
			(layer "F.Fab")
		)
		(fp_line
			(start -0.12065 0.3048)
			(end -0.67945 0.3048)
			(stroke
				(width 0.1)
				(type default)
			)
			(layer "F.Fab")
		)
		(fp_line
			(start 0.120396 0.2794)
			(end -0.12065 0.2794)
			(stroke
				(width 0.1)
				(type default)
			)
			(layer "F.Fab")
		)
		(fp_line
			(start 0.120396 0.3048)
			(end 0.120396 0.2794)
			(stroke
				(width 0.1)
				(type default)
			)
			(layer "F.Fab")
		)
		(fp_line
			(start 0.12065 -0.3048)
			(end 0.67945 -0.3048)
			(stroke
				(width 0.1)
				(type default)
			)
			(layer "F.Fab")
		)
		(fp_line
			(start 0.12065 -0.2794)
			(end 0.12065 -0.3048)
			(stroke
				(width 0.1)
				(type default)
			)
			(layer "F.Fab")
		)
		(fp_line
			(start 0.67945 -0.3048)
			(end 0.67945 0.3048)
			(stroke
				(width 0.1)
				(type default)
			)
			(layer "F.Fab")
		)
		(fp_line
			(start 0.67945 0.3048)
			(end 0.120396 0.3048)
			(stroke
				(width 0.1)
				(type default)
			)
			(layer "F.Fab")
		)
		(pad "1" smd circle
			(at -0.40005 0)
			(size 0 0)
			(layers "F.Cu" "F.Mask" "F.Paste")
			(net "P3V3_AUX")
		)
		(pad "2" smd circle
			(at 0.40005 0)
			(size 0 0)
			(layers "F.Cu" "F.Mask" "F.Paste")
			(net "GPU_WP_HW_CTRL_N")
		)
	)
	(footprint ""
		(layer "F.Cu")
		(at 69.397118 -402.371052 -90)
		(property "Reference" "C724"
			(at 0 0 270)
			(layer "F.SilkS")
			(hide yes)
			(effects
				(font
					(size 1.27 1.27)
				)
			)
		)
		(property "Value" ""
			(at 0 0 270)
			(layer "F.Fab")
			(effects
				(font
					(size 1.27 1.27)
				)
			)
		)
		(duplicate_pad_numbers_are_jumpers no)
		(fp_line
			(start -0.299974 0.150114)
			(end -0.299974 -0.150114)
			(stroke
				(width 0.1)
				(type default)
			)
			(layer "F.Fab")
		)
		(fp_line
			(start 0.299974 0.150114)
			(end -0.299974 0.150114)
			(stroke
				(width 0.1)
				(type default)
			)
			(layer "F.Fab")
		)
		(fp_line
			(start -0.299974 -0.150114)
			(end 0.299974 -0.150114)
			(stroke
				(width 0.1)
				(type default)
			)
			(layer "F.Fab")
		)
		(fp_line
			(start 0.299974 -0.150114)
			(end 0.299974 0.150114)
			(stroke
				(width 0.1)
				(type default)
			)
			(layer "F.Fab")
		)
		(pad "1" smd rect
			(at -0.2667 0 270)
			(size 0.3048 0.381)
			(layers "F.Cu" "F.Mask" "F.Paste")
			(net "P5E_CPU1_PE0_TX_C_DN<8>")
		)
		(pad "2" smd rect
			(at 0.2667 0 270)
			(size 0.3048 0.381)
			(layers "F.Cu" "F.Mask" "F.Paste")
			(net "P5E_CPU1_PE0_TX_DN<8>")
		)
	)
	(footprint ""
		(layer "F.Cu")
		(at 217.889582 -69.397118)
		(property "Reference" "PC2212"
			(at 0 0 0)
			(layer "F.SilkS")
			(hide yes)
			(effects
				(font
					(size 1.27 1.27)
				)
			)
		)
		(property "Value" ""
			(at 0 0 0)
			(layer "F.Fab")
			(effects
				(font
					(size 1.27 1.27)
				)
			)
		)
		(duplicate_pad_numbers_are_jumpers no)
		(fp_line
			(start -0.7874 -0.4064)
			(end 0.7874 -0.4064)
			(stroke
				(width 0.1524)
				(type default)
			)
			(layer "F.SilkS")
		)
		(fp_line
			(start -0.7874 0.4064)
			(end -0.7874 -0.4064)
			(stroke
				(width 0.1524)
				(type default)
			)
			(layer "F.SilkS")
		)
		(fp_line
			(start 0.7874 -0.4064)
			(end 0.7874 0.4064)
			(stroke
				(width 0.1524)
				(type default)
			)
			(layer "F.SilkS")
		)
		(fp_line
			(start 0.7874 0.4064)
			(end -0.7874 0.4064)
			(stroke
				(width 0.1524)
				(type default)
			)
			(layer "F.SilkS")
		)
		(fp_line
			(start -0.67945 -0.305054)
			(end -0.12065 -0.305054)
			(stroke
				(width 0.1)
				(type default)
			)
			(layer "F.Fab")
		)
		(fp_line
			(start -0.67945 0.3048)
			(end -0.67945 -0.305054)
			(stroke
				(width 0.1)
				(type default)
			)
			(layer "F.Fab")
		)
		(fp_line
			(start -0.12065 -0.305054)
			(end -0.12065 -0.2794)
			(stroke
				(width 0.1)
				(type default)
			)
			(layer "F.Fab")
		)
		(fp_line
			(start -0.12065 -0.2794)
			(end 0.12065 -0.2794)
			(stroke
				(width 0.1)
				(type default)
			)
			(layer "F.Fab")
		)
		(fp_line
			(start -0.12065 0.2794)
			(end -0.12065 0.3048)
			(stroke
				(width 0.1)
				(type default)
			)
			(layer "F.Fab")
		)
		(fp_line
			(start -0.12065 0.3048)
			(end -0.67945 0.3048)
			(stroke
				(width 0.1)
				(type default)
			)
			(layer "F.Fab")
		)
		(fp_line
			(start 0.120396 0.2794)
			(end -0.12065 0.2794)
			(stroke
				(width 0.1)
				(type default)
			)
			(layer "F.Fab")
		)
		(fp_line
			(start 0.120396 0.3048)
			(end 0.120396 0.2794)
			(stroke
				(width 0.1)
				(type default)
			)
			(layer "F.Fab")
		)
		(fp_line
			(start 0.12065 -0.3048)
			(end 0.67945 -0.3048)
			(stroke
				(width 0.1)
				(type default)
			)
			(layer "F.Fab")
		)
		(fp_line
			(start 0.12065 -0.2794)
			(end 0.12065 -0.3048)
			(stroke
				(width 0.1)
				(type default)
			)
			(layer "F.Fab")
		)
		(fp_line
			(start 0.67945 -0.3048)
			(end 0.67945 0.3048)
			(stroke
				(width 0.1)
				(type default)
			)
			(layer "F.Fab")
		)
		(fp_line
			(start 0.67945 0.3048)
			(end 0.120396 0.3048)
			(stroke
				(width 0.1)
				(type default)
			)
			(layer "F.Fab")
		)
		(pad "1" smd circle
			(at -0.40005 0)
			(size 0 0)
			(layers "F.Cu" "F.Mask" "F.Paste")
			(net "GND")
		)
		(pad "2" smd circle
			(at 0.40005 0)
			(size 0 0)
			(layers "F.Cu" "F.Mask" "F.Paste")
			(net "P3V3_E1S_REG_0")
		)
	)
)
